(kicad_pcb
	(version 20260206)
	(generator "pcbnew")
	(generator_version "10.0")
	(general
		(thickness 1.6)
		(legacy_teardrops no)
	)
	(paper "A4")
	(title_block
		(title "12092022_DA0F0TMDCD0_F0T_Management_Board_D_brd_V3_OCP.brd")
		(comment 1 "Grand Teton / footprints 1088-1092 of 1440")
	)
	(layers
		(0 "F.Cu" signal "TOP")
		(4 "In1.Cu" signal "GND")
		(6 "In2.Cu" signal "IN1")
		(8 "In3.Cu" signal "GND1")
		(10 "In4.Cu" signal "IN2")
		(12 "In5.Cu" signal "VCC")
		(14 "In6.Cu" signal "VCC1")
		(16 "In7.Cu" signal "IN3")
		(18 "In8.Cu" signal "GND2")
		(20 "In9.Cu" signal "IN4")
		(22 "In10.Cu" signal "GND3")
		(2 "B.Cu" signal "BOTTOM")
		(9 "F.Adhes" user "F.Adhesive")
		(11 "B.Adhes" user "B.Adhesive")
		(13 "F.Paste" user "Package Geometry/Pastemask Top")
		(15 "B.Paste" user "Package Geometry/Pastemask Bottom")
		(5 "F.SilkS" user "Ref Des/Silkscreen Top")
		(7 "B.SilkS" user "Ref Des/Silkscreen Bottom")
		(1 "F.Mask" user "Board Geometry/Soldermask Top")
		(3 "B.Mask" user "Board Geometry/Soldermask Bottom")
		(17 "Dwgs.User" user "User.Drawings")
		(19 "Cmts.User" user "User.Comments")
		(21 "Eco1.User" user "User.Eco1")
		(23 "Eco2.User" user "User.Eco2")
		(25 "Edge.Cuts" user "Board Geometry/Outline")
		(27 "Margin" user)
		(31 "F.CrtYd" user "Package Geometry/Place Bound Top")
		(29 "B.CrtYd" user "Package Geometry/Place Bound Bottom")
		(35 "F.Fab" user "Ref Des/Assembly Top")
		(33 "B.Fab" user "Ref Des/Assembly Bottom")
	)
	(footprint ""
		(layer "B.Cu")
		(at 71.73976 -37.271706 -90)
		(property "Reference" "C127"
			(at 0 0 90)
			(layer "B.SilkS")
			(hide yes)
			(effects
				(font
					(size 1.27 1.27)
				)
				(justify mirror)
			)
		)
		(property "Value" ""
			(at 0 0 90)
			(layer "B.Fab")
			(effects
				(font
					(size 1.27 1.27)
				)
				(justify mirror)
			)
		)
		(duplicate_pad_numbers_are_jumpers no)
		(fp_line
			(start -0.7874 0.4064)
			(end 0.7874 0.4064)
			(stroke
				(width 0.1524)
				(type default)
			)
			(layer "B.SilkS")
		)
		(fp_line
			(start 0.7874 0.4064)
			(end 0.7874 -0.4064)
			(stroke
				(width 0.1524)
				(type default)
			)
			(layer "B.SilkS")
		)
		(fp_line
			(start -0.7874 -0.4064)
			(end -0.7874 0.4064)
			(stroke
				(width 0.1524)
				(type default)
			)
			(layer "B.SilkS")
		)
		(fp_line
			(start 0.7874 -0.4064)
			(end -0.7874 -0.4064)
			(stroke
				(width 0.1524)
				(type default)
			)
			(layer "B.SilkS")
		)
		(fp_line
			(start -0.67945 0.3048)
			(end -0.120396 0.3048)
			(stroke
				(width 0.1)
				(type default)
			)
			(layer "B.Fab")
		)
		(fp_line
			(start -0.120396 0.3048)
			(end -0.120396 0.2794)
			(stroke
				(width 0.1)
				(type default)
			)
			(layer "B.Fab")
		)
		(fp_line
			(start 0.12065 0.3048)
			(end 0.67945 0.3048)
			(stroke
				(width 0.1)
				(type default)
			)
			(layer "B.Fab")
		)
		(fp_line
			(start 0.67945 0.3048)
			(end 0.67945 -0.305054)
			(stroke
				(width 0.1)
				(type default)
			)
			(layer "B.Fab")
		)
		(fp_line
			(start -0.120396 0.2794)
			(end 0.12065 0.2794)
			(stroke
				(width 0.1)
				(type default)
			)
			(layer "B.Fab")
		)
		(fp_line
			(start 0.12065 0.2794)
			(end 0.12065 0.3048)
			(stroke
				(width 0.1)
				(type default)
			)
			(layer "B.Fab")
		)
		(fp_line
			(start -0.12065 -0.2794)
			(end -0.12065 -0.3048)
			(stroke
				(width 0.1)
				(type default)
			)
			(layer "B.Fab")
		)
		(fp_line
			(start 0.12065 -0.2794)
			(end -0.12065 -0.2794)
			(stroke
				(width 0.1)
				(type default)
			)
			(layer "B.Fab")
		)
		(fp_line
			(start -0.67945 -0.3048)
			(end -0.67945 0.3048)
			(stroke
				(width 0.1)
				(type default)
			)
			(layer "B.Fab")
		)
		(fp_line
			(start -0.12065 -0.3048)
			(end -0.67945 -0.3048)
			(stroke
				(width 0.1)
				(type default)
			)
			(layer "B.Fab")
		)
		(fp_line
			(start 0.12065 -0.305054)
			(end 0.12065 -0.2794)
			(stroke
				(width 0.1)
				(type default)
			)
			(layer "B.Fab")
		)
		(fp_line
			(start 0.67945 -0.305054)
			(end 0.12065 -0.305054)
			(stroke
				(width 0.1)
				(type default)
			)
			(layer "B.Fab")
		)
		(pad "1" smd circle
			(at 0.40005 0 90)
			(size 0 0)
			(layers "B.Cu" "B.Mask" "B.Paste")
			(net "P1V2_AUX")
		)
		(pad "2" smd circle
			(at -0.40005 0 90)
			(size 0 0)
			(layers "B.Cu" "B.Mask" "B.Paste")
			(net "GND")
		)
	)
	(footprint ""
		(layer "B.Cu")
		(at 45.212 -86.44255 90)
		(property "Reference" "R754"
			(at 0 0 90)
			(layer "B.SilkS")
			(hide yes)
			(effects
				(font
					(size 1.27 1.27)
				)
				(justify mirror)
			)
		)
		(property "Value" ""
			(at 0 0 90)
			(layer "B.Fab")
			(effects
				(font
					(size 1.27 1.27)
				)
				(justify mirror)
			)
		)
		(duplicate_pad_numbers_are_jumpers no)
		(fp_line
			(start 0.7874 -0.4064)
			(end -0.7874 -0.4064)
			(stroke
				(width 0.1524)
				(type default)
			)
			(layer "B.SilkS")
		)
		(fp_line
			(start -0.7874 -0.4064)
			(end -0.7874 0.4064)
			(stroke
				(width 0.1524)
				(type default)
			)
			(layer "B.SilkS")
		)
		(fp_line
			(start 0.7874 0.4064)
			(end 0.7874 -0.4064)
			(stroke
				(width 0.1524)
				(type default)
			)
			(layer "B.SilkS")
		)
		(fp_line
			(start -0.7874 0.4064)
			(end 0.7874 0.4064)
			(stroke
				(width 0.1524)
				(type default)
			)
			(layer "B.SilkS")
		)
		(fp_line
			(start 0.67945 -0.305054)
			(end 0.12065 -0.305054)
			(stroke
				(width 0.1)
				(type default)
			)
			(layer "B.Fab")
		)
		(fp_line
			(start 0.12065 -0.305054)
			(end 0.12065 -0.2794)
			(stroke
				(width 0.1)
				(type default)
			)
			(layer "B.Fab")
		)
		(fp_line
			(start -0.12065 -0.3048)
			(end -0.67945 -0.3048)
			(stroke
				(width 0.1)
				(type default)
			)
			(layer "B.Fab")
		)
		(fp_line
			(start -0.67945 -0.3048)
			(end -0.67945 0.3048)
			(stroke
				(width 0.1)
				(type default)
			)
			(layer "B.Fab")
		)
		(fp_line
			(start 0.12065 -0.2794)
			(end -0.12065 -0.2794)
			(stroke
				(width 0.1)
				(type default)
			)
			(layer "B.Fab")
		)
		(fp_line
			(start -0.12065 -0.2794)
			(end -0.12065 -0.3048)
			(stroke
				(width 0.1)
				(type default)
			)
			(layer "B.Fab")
		)
		(fp_line
			(start 0.12065 0.2794)
			(end 0.12065 0.3048)
			(stroke
				(width 0.1)
				(type default)
			)
			(layer "B.Fab")
		)
		(fp_line
			(start -0.120396 0.2794)
			(end 0.12065 0.2794)
			(stroke
				(width 0.1)
				(type default)
			)
			(layer "B.Fab")
		)
		(fp_line
			(start 0.67945 0.3048)
			(end 0.67945 -0.305054)
			(stroke
				(width 0.1)
				(type default)
			)
			(layer "B.Fab")
		)
		(fp_line
			(start 0.12065 0.3048)
			(end 0.67945 0.3048)
			(stroke
				(width 0.1)
				(type default)
			)
			(layer "B.Fab")
		)
		(fp_line
			(start -0.120396 0.3048)
			(end -0.120396 0.2794)
			(stroke
				(width 0.1)
				(type default)
			)
			(layer "B.Fab")
		)
		(fp_line
			(start -0.67945 0.3048)
			(end -0.120396 0.3048)
			(stroke
				(width 0.1)
				(type default)
			)
			(layer "B.Fab")
		)
		(pad "1" smd circle
			(at 0.40005 0 270)
			(size 0 0)
			(layers "B.Cu" "B.Mask" "B.Paste")
			(net "P3V3_RGM")
		)
		(pad "2" smd circle
			(at -0.40005 0 270)
			(size 0 0)
			(layers "B.Cu" "B.Mask" "B.Paste")
			(net "UART_BMC_5_TXD_R")
		)
	)
	(footprint ""
		(layer "B.Cu")
		(at 52.959 -66.1416 -90)
		(property "Reference" "R38"
			(at 0 0 90)
			(layer "B.SilkS")
			(hide yes)
			(effects
				(font
					(size 1.27 1.27)
				)
				(justify mirror)
			)
		)
		(property "Value" ""
			(at 0 0 90)
			(layer "B.Fab")
			(effects
				(font
					(size 1.27 1.27)
				)
				(justify mirror)
			)
		)
		(duplicate_pad_numbers_are_jumpers no)
		(fp_line
			(start -0.7874 0.4064)
			(end 0.7874 0.4064)
			(stroke
				(width 0.1524)
				(type default)
			)
			(layer "B.SilkS")
		)
		(fp_line
			(start 0.7874 0.4064)
			(end 0.7874 -0.4064)
			(stroke
				(width 0.1524)
				(type default)
			)
			(layer "B.SilkS")
		)
		(fp_line
			(start -0.7874 -0.4064)
			(end -0.7874 0.4064)
			(stroke
				(width 0.1524)
				(type default)
			)
			(layer "B.SilkS")
		)
		(fp_line
			(start 0.7874 -0.4064)
			(end -0.7874 -0.4064)
			(stroke
				(width 0.1524)
				(type default)
			)
			(layer "B.SilkS")
		)
		(fp_line
			(start -0.67945 0.3048)
			(end -0.120396 0.3048)
			(stroke
				(width 0.1)
				(type default)
			)
			(layer "B.Fab")
		)
		(fp_line
			(start -0.120396 0.3048)
			(end -0.120396 0.2794)
			(stroke
				(width 0.1)
				(type default)
			)
			(layer "B.Fab")
		)
		(fp_line
			(start 0.12065 0.3048)
			(end 0.67945 0.3048)
			(stroke
				(width 0.1)
				(type default)
			)
			(layer "B.Fab")
		)
		(fp_line
			(start 0.67945 0.3048)
			(end 0.67945 -0.305054)
			(stroke
				(width 0.1)
				(type default)
			)
			(layer "B.Fab")
		)
		(fp_line
			(start -0.120396 0.2794)
			(end 0.12065 0.2794)
			(stroke
				(width 0.1)
				(type default)
			)
			(layer "B.Fab")
		)
		(fp_line
			(start 0.12065 0.2794)
			(end 0.12065 0.3048)
			(stroke
				(width 0.1)
				(type default)
			)
			(layer "B.Fab")
		)
		(fp_line
			(start -0.12065 -0.2794)
			(end -0.12065 -0.3048)
			(stroke
				(width 0.1)
				(type default)
			)
			(layer "B.Fab")
		)
		(fp_line
			(start 0.12065 -0.2794)
			(end -0.12065 -0.2794)
			(stroke
				(width 0.1)
				(type default)
			)
			(layer "B.Fab")
		)
		(fp_line
			(start -0.67945 -0.3048)
			(end -0.67945 0.3048)
			(stroke
				(width 0.1)
				(type default)
			)
			(layer "B.Fab")
		)
		(fp_line
			(start -0.12065 -0.3048)
			(end -0.67945 -0.3048)
			(stroke
				(width 0.1)
				(type default)
			)
			(layer "B.Fab")
		)
		(fp_line
			(start 0.12065 -0.305054)
			(end 0.12065 -0.2794)
			(stroke
				(width 0.1)
				(type default)
			)
			(layer "B.Fab")
		)
		(fp_line
			(start 0.67945 -0.305054)
			(end 0.12065 -0.305054)
			(stroke
				(width 0.1)
				(type default)
			)
			(layer "B.Fab")
		)
		(pad "1" smd circle
			(at 0.40005 0 90)
			(size 0 0)
			(layers "B.Cu" "B.Mask" "B.Paste")
			(net "P3V3_AUX")
		)
		(pad "2" smd circle
			(at -0.40005 0 90)
			(size 0 0)
			(layers "B.Cu" "B.Mask" "B.Paste")
			(net "FM_BMC_SUSACK_N")
		)
	)
	(footprint ""
		(layer "B.Cu")
		(at 112.014 -85.344 90)
		(property "Reference" "X1"
			(at 1.73863 2.4638 0)
			(unlocked yes)
			(layer "B.SilkS")
			(effects
				(font
					(size 0.7874 0.5842)
					(thickness 0.1524)
				)
				(justify left mirror)
			)
		)
		(property "Value" ""
			(at 0 0 90)
			(layer "B.Fab")
			(effects
				(font
					(size 1.27 1.27)
				)
				(justify mirror)
			)
		)
		(property "Device Type" "TP_TDR_4P_FTS_TH-TP_TDR_4P_DIPA"
			(at -1.30175 1.27 0)
			(unlocked yes)
			(layer "B.Fab")
			(hide yes)
			(effects
				(font
					(size 0.635 0.4064)
					(thickness 0.1524)
				)
				(justify mirror)
			)
		)
		(property "User Part Number" "N_A"
			(at -1.30175 1.27 0)
			(unlocked yes)
			(layer "Cmts.User")
			(hide yes)
			(effects
				(font
					(size 0.635 0.4064)
					(thickness 0.1524)
				)
				(justify mirror)
			)
		)
		(duplicate_pad_numbers_are_jumpers no)
		(fp_line
			(start 0 -1.27)
			(end 0 -0.635)
			(stroke
				(width 0.1524)
				(type default)
			)
			(layer "B.SilkS")
		)
		(fp_line
			(start -2.54 -1.27)
			(end 0 -1.27)
			(stroke
				(width 0.1524)
				(type default)
			)
			(layer "B.SilkS")
		)
		(fp_line
			(start -2.54 -1.1303)
			(end -2.54 -1.27)
			(stroke
				(width 0.1524)
				(type default)
			)
			(layer "B.SilkS")
		)
		(fp_line
			(start 0 0.635)
			(end 0 1.905)
			(stroke
				(width 0.1524)
				(type default)
			)
			(layer "B.SilkS")
		)
		(fp_line
			(start -2.54 1.4097)
			(end -2.54 1.1303)
			(stroke
				(width 0.1524)
				(type default)
			)
			(layer "B.SilkS")
		)
		(fp_line
			(start 0 3.175)
			(end 0 3.81)
			(stroke
				(width 0.1524)
				(type default)
			)
			(layer "B.SilkS")
		)
		(fp_line
			(start 0 3.81)
			(end -2.54 3.81)
			(stroke
				(width 0.1524)
				(type default)
			)
			(layer "B.SilkS")
		)
		(fp_line
			(start -2.54 3.81)
			(end -2.54 3.6703)
			(stroke
				(width 0.1524)
				(type default)
			)
			(layer "B.SilkS")
		)
		(fp_poly
			(pts
				(xy 0.761746 0) (xy 2.285746 -0.762) (xy 2.285746 0.762)
			)
			(stroke
				(width 0)
				(type default)
			)
			(fill yes)
			(layer "B.SilkS")
		)
		(fp_line
			(start 0 -1.27)
			(end 0 3.81)
			(stroke
				(width 0.1)
				(type default)
			)
			(layer "B.Fab")
		)
		(fp_line
			(start -2.54 -1.27)
			(end 0 -1.27)
			(stroke
				(width 0.1)
				(type default)
			)
			(layer "B.Fab")
		)
		(fp_line
			(start 0 3.81)
			(end -2.54 3.81)
			(stroke
				(width 0.1)
				(type default)
			)
			(layer "B.Fab")
		)
		(fp_line
			(start -2.54 3.81)
			(end -2.54 -1.27)
			(stroke
				(width 0.1)
				(type default)
			)
			(layer "B.Fab")
		)
		(fp_poly
			(pts
				(xy 0.761746 0) (xy 2.285746 -0.762) (xy 2.285746 0.762)
			)
			(stroke
				(width 0)
				(type default)
			)
			(fill yes)
			(layer "B.Fab")
		)
		(pad "1" thru_hole circle
			(at 0 0 270)
			(size 1.0033 1.0033)
			(drill 0.249936)
			(layers "*.Cu" "*.Mask")
			(remove_unused_layers no)
			(net "TDR_DIFF_85_TOP_DP")
			(clearance 0.10795)
			(padstack
				(mode front_inner_back)
				(layer "Inner"
					(shape circle)
					(size 0.8001 0.8001)
					(clearance 0.1524)
				)
				(layer "B.Cu"
					(shape circle)
					(size 1.0033 1.0033)
					(thermal_gap 0.10795)
					(clearance 0.10795)
				)
			)
		)
		(pad "2" thru_hole circle
			(at -2.54 0 270)
			(size 1.9939 1.9939)
			(drill 0.249936)
			(layers "*.Cu" "*.Mask")
			(remove_unused_layers no)
			(net "GND_P1")
			(clearance 0.10795)
			(padstack
				(mode front_inner_back)
				(layer "Inner"
					(shape circle)
					(size 0.8001 0.8001)
					(clearance 0.1524)
				)
				(layer "B.Cu"
					(shape circle)
					(size 1.9939 1.9939)
					(thermal_gap 0.10795)
					(clearance 0.10795)
				)
			)
		)
		(pad "3" thru_hole circle
			(at -2.54 2.54 270)
			(size 1.9939 1.9939)
			(drill 0.249936)
			(layers "*.Cu" "*.Mask")
			(remove_unused_layers no)
			(net "GND_P1")
			(clearance 0.10795)
			(padstack
				(mode front_inner_back)
				(layer "Inner"
					(shape circle)
					(size 0.8001 0.8001)
					(clearance 0.1524)
				)
				(layer "B.Cu"
					(shape circle)
					(size 1.9939 1.9939)
					(thermal_gap 0.10795)
					(clearance 0.10795)
				)
			)
		)
		(pad "4" thru_hole circle
			(at 0 2.54 270)
			(size 1.0033 1.0033)
			(drill 0.249936)
			(layers "*.Cu" "*.Mask")
			(remove_unused_layers no)
			(net "TDR_DIFF_85_TOP_DN")
			(clearance 0.10795)
			(padstack
				(mode front_inner_back)
				(layer "Inner"
					(shape circle)
					(size 0.8001 0.8001)
					(clearance 0.1524)
				)
				(layer "B.Cu"
					(shape circle)
					(size 1.0033 1.0033)
					(thermal_gap 0.10795)
					(clearance 0.10795)
				)
			)
		)
	)
	(footprint ""
		(layer "B.Cu")
		(at 26.8224 -84.3788 -90)
		(property "Reference" "R625"
			(at 0 0 90)
			(layer "B.SilkS")
			(hide yes)
			(effects
				(font
					(size 1.27 1.27)
				)
				(justify mirror)
			)
		)
		(property "Value" ""
			(at 0 0 90)
			(layer "B.Fab")
			(effects
				(font
					(size 1.27 1.27)
				)
				(justify mirror)
			)
		)
		(duplicate_pad_numbers_are_jumpers no)
		(fp_line
			(start -0.7874 0.4064)
			(end 0.7874 0.4064)
			(stroke
				(width 0.1524)
				(type default)
			)
			(layer "B.SilkS")
		)
		(fp_line
			(start 0.7874 0.4064)
			(end 0.7874 -0.4064)
			(stroke
				(width 0.1524)
				(type default)
			)
			(layer "B.SilkS")
		)
		(fp_line
			(start -0.7874 -0.4064)
			(end -0.7874 0.4064)
			(stroke
				(width 0.1524)
				(type default)
			)
			(layer "B.SilkS")
		)
		(fp_line
			(start 0.7874 -0.4064)
			(end -0.7874 -0.4064)
			(stroke
				(width 0.1524)
				(type default)
			)
			(layer "B.SilkS")
		)
		(fp_line
			(start -0.67945 0.3048)
			(end -0.120396 0.3048)
			(stroke
				(width 0.1)
				(type default)
			)
			(layer "B.Fab")
		)
		(fp_line
			(start -0.120396 0.3048)
			(end -0.120396 0.2794)
			(stroke
				(width 0.1)
				(type default)
			)
			(layer "B.Fab")
		)
		(fp_line
			(start 0.12065 0.3048)
			(end 0.67945 0.3048)
			(stroke
				(width 0.1)
				(type default)
			)
			(layer "B.Fab")
		)
		(fp_line
			(start 0.67945 0.3048)
			(end 0.67945 -0.305054)
			(stroke
				(width 0.1)
				(type default)
			)
			(layer "B.Fab")
		)
		(fp_line
			(start -0.120396 0.2794)
			(end 0.12065 0.2794)
			(stroke
				(width 0.1)
				(type default)
			)
			(layer "B.Fab")
		)
		(fp_line
			(start 0.12065 0.2794)
			(end 0.12065 0.3048)
			(stroke
				(width 0.1)
				(type default)
			)
			(layer "B.Fab")
		)
		(fp_line
			(start -0.12065 -0.2794)
			(end -0.12065 -0.3048)
			(stroke
				(width 0.1)
				(type default)
			)
			(layer "B.Fab")
		)
		(fp_line
			(start 0.12065 -0.2794)
			(end -0.12065 -0.2794)
			(stroke
				(width 0.1)
				(type default)
			)
			(layer "B.Fab")
		)
		(fp_line
			(start -0.67945 -0.3048)
			(end -0.67945 0.3048)
			(stroke
				(width 0.1)
				(type default)
			)
			(layer "B.Fab")
		)
		(fp_line
			(start -0.12065 -0.3048)
			(end -0.67945 -0.3048)
			(stroke
				(width 0.1)
				(type default)
			)
			(layer "B.Fab")
		)
		(fp_line
			(start 0.12065 -0.305054)
			(end 0.12065 -0.2794)
			(stroke
				(width 0.1)
				(type default)
			)
			(layer "B.Fab")
		)
		(fp_line
			(start 0.67945 -0.305054)
			(end 0.12065 -0.305054)
			(stroke
				(width 0.1)
				(type default)
			)
			(layer "B.Fab")
		)
		(pad "1" smd circle
			(at 0.40005 0 90)
			(size 0 0)
			(layers "B.Cu" "B.Mask" "B.Paste")
			(net "P3V3_AUX")
		)
		(pad "2" smd circle
			(at -0.40005 0 90)
			(size 0 0)
			(layers "B.Cu" "B.Mask" "B.Paste")
			(net "RST_RSMRST_N")
		)
	)
)
